# T6G (Grand Teton) — schematic netlist excerpt (pin names and nets, part order shuffled) for the footprints in the layout excerpt that follows; sources: Cadence DE-HDL packaged netlist, KiCad conversion of 04192023_DAF0TMB3IC0_F0TG_MB_C_brd_V02_OCP.brd

R941  Q_RES  0 5% EMPTY  pkg 0402LF  page 166 : A = BOOT_RDY_H ; B = BOOT_RDY_R1_N
C2579  Q_CAP  22UF 4V 20% X6S  pkg C0402  page 70 : A = PVDDCR_SOC_P0 ; B = GND

(kicad_pcb
	(version 20260206)
	(generator "pcbnew")
	(generator_version "10.0")
	(general
		(thickness 1.6)
		(legacy_teardrops no)
	)
	(paper "A4")
	(title_block
		(title "04192023_DAF0TMB3IC0_F0TG_MB_C_brd_V02_OCP.brd")
		(comment 1 "Grand Teton / footprints 7973-7974 of 8354")
	)
	(layers
		(0 "F.Cu" signal "TOP")
		(4 "In1.Cu" signal "GND")
		(6 "In2.Cu" signal "IN1")
		(8 "In3.Cu" signal "GND1")
		(10 "In4.Cu" signal "IN2")
		(12 "In5.Cu" signal "GND2")
		(14 "In6.Cu" signal "IN3")
		(16 "In7.Cu" signal "GND3")
		(18 "In8.Cu" signal "VCC")
		(20 "In9.Cu" signal "VCC1")
		(22 "In10.Cu" signal "GND4")
		(24 "In11.Cu" signal "IN4")
		(26 "In12.Cu" signal "GND5")
		(28 "In13.Cu" signal "IN5")
		(30 "In14.Cu" signal "GND6")
		(32 "In15.Cu" signal "IN6")
		(34 "In16.Cu" signal "GND7")
		(2 "B.Cu" signal "BOTTOM")
		(9 "F.Adhes" user "F.Adhesive")
		(11 "B.Adhes" user "B.Adhesive")
		(13 "F.Paste" user "Package Geometry/Pastemask Top")
		(15 "B.Paste" user "Package Geometry/Pastemask Bottom")
		(5 "F.SilkS" user "Ref Des/Silkscreen Top")
		(7 "B.SilkS" user "Ref Des/Silkscreen Bottom")
		(1 "F.Mask" user "Board Geometry/Soldermask Top")
		(3 "B.Mask" user "Board Geometry/Soldermask Bottom")
		(17 "Dwgs.User" user "User.Drawings")
		(19 "Cmts.User" user "User.Comments")
		(21 "Eco1.User" user "User.Eco1")
		(23 "Eco2.User" user "User.Eco2")
		(25 "Edge.Cuts" user "Board Geometry/Outline")
		(27 "Margin" user)
		(31 "F.CrtYd" user "Package Geometry/Place Bound Top")
		(29 "B.CrtYd" user "Package Geometry/Place Bound Bottom")
		(35 "F.Fab" user "Ref Des/Assembly Top")
		(33 "B.Fab" user "Ref Des/Assembly Bottom")
	)
	(footprint ""
		(layer "B.Cu")
		(at 399.522696 -341.172292 90)
		(property "Reference" "R941"
			(at 0 0 90)
			(layer "B.SilkS")
			(hide yes)
			(effects
				(font
					(size 1.27 1.27)
				)
				(justify mirror)
			)
		)
		(property "Value" ""
			(at 0 0 90)
			(layer "B.Fab")
			(effects
				(font
					(size 1.27 1.27)
				)
				(justify mirror)
			)
		)
		(duplicate_pad_numbers_are_jumpers no)
		(fp_line
			(start 0.7874 -0.4064)
			(end -0.7874 -0.4064)
			(stroke
				(width 0.1524)
				(type default)
			)
			(layer "B.SilkS")
		)
		(fp_line
			(start -0.7874 -0.4064)
			(end -0.7874 0.4064)
			(stroke
				(width 0.1524)
				(type default)
			)
			(layer "B.SilkS")
		)
		(fp_line
			(start 0.7874 0.4064)
			(end 0.7874 -0.4064)
			(stroke
				(width 0.1524)
				(type default)
			)
			(layer "B.SilkS")
		)
		(fp_line
			(start -0.7874 0.4064)
			(end 0.7874 0.4064)
			(stroke
				(width 0.1524)
				(type default)
			)
			(layer "B.SilkS")
		)
		(fp_line
			(start 0.67945 -0.305054)
			(end 0.12065 -0.305054)
			(stroke
				(width 0.1)
				(type default)
			)
			(layer "B.Fab")
		)
		(fp_line
			(start 0.12065 -0.305054)
			(end 0.12065 -0.2794)
			(stroke
				(width 0.1)
				(type default)
			)
			(layer "B.Fab")
		)
		(fp_line
			(start -0.12065 -0.3048)
			(end -0.67945 -0.3048)
			(stroke
				(width 0.1)
				(type default)
			)
			(layer "B.Fab")
		)
		(fp_line
			(start -0.67945 -0.3048)
			(end -0.67945 0.3048)
			(stroke
				(width 0.1)
				(type default)
			)
			(layer "B.Fab")
		)
		(fp_line
			(start 0.12065 -0.2794)
			(end -0.12065 -0.2794)
			(stroke
				(width 0.1)
				(type default)
			)
			(layer "B.Fab")
		)
		(fp_line
			(start -0.12065 -0.2794)
			(end -0.12065 -0.3048)
			(stroke
				(width 0.1)
				(type default)
			)
			(layer "B.Fab")
		)
		(fp_line
			(start 0.12065 0.2794)
			(end 0.12065 0.3048)
			(stroke
				(width 0.1)
				(type default)
			)
			(layer "B.Fab")
		)
		(fp_line
			(start -0.120396 0.2794)
			(end 0.12065 0.2794)
			(stroke
				(width 0.1)
				(type default)
			)
			(layer "B.Fab")
		)
		(fp_line
			(start 0.67945 0.3048)
			(end 0.67945 -0.305054)
			(stroke
				(width 0.1)
				(type default)
			)
			(layer "B.Fab")
		)
		(fp_line
			(start 0.12065 0.3048)
			(end 0.67945 0.3048)
			(stroke
				(width 0.1)
				(type default)
			)
			(layer "B.Fab")
		)
		(fp_line
			(start -0.120396 0.3048)
			(end -0.120396 0.2794)
			(stroke
				(width 0.1)
				(type default)
			)
			(layer "B.Fab")
		)
		(fp_line
			(start -0.67945 0.3048)
			(end -0.120396 0.3048)
			(stroke
				(width 0.1)
				(type default)
			)
			(layer "B.Fab")
		)
		(pad "1" smd circle
			(at 0.40005 0 270)
			(size 0 0)
			(layers "B.Cu" "B.Mask" "B.Paste")
			(net "BOOT_RDY_H")
		)
		(pad "2" smd circle
			(at -0.40005 0 270)
			(size 0 0)
			(layers "B.Cu" "B.Mask" "B.Paste")
			(net "BOOT_RDY_R1_N")
		)
	)
	(footprint ""
		(layer "B.Cu")
		(at 371.551454 -254.19431)
		(property "Reference" "C2579"
			(at 0 0 0)
			(layer "B.SilkS")
			(hide yes)
			(effects
				(font
					(size 1.27 1.27)
				)
				(justify mirror)
			)
		)
		(property "Value" ""
			(at 0 0 0)
			(layer "B.Fab")
			(effects
				(font
					(size 1.27 1.27)
				)
				(justify mirror)
			)
		)
		(duplicate_pad_numbers_are_jumpers no)
		(fp_line
			(start -0.7874 -0.4064)
			(end -0.7874 0.4064)
			(stroke
				(width 0.1524)
				(type default)
			)
			(layer "B.SilkS")
		)
		(fp_line
			(start -0.7874 0.4064)
			(end 0.7874 0.4064)
			(stroke
				(width 0.1524)
				(type default)
			)
			(layer "B.SilkS")
		)
		(fp_line
			(start 0.7874 -0.4064)
			(end -0.7874 -0.4064)
			(stroke
				(width 0.1524)
				(type default)
			)
			(layer "B.SilkS")
		)
		(fp_line
			(start 0.7874 0.4064)
			(end 0.7874 -0.4064)
			(stroke
				(width 0.1524)
				(type default)
			)
			(layer "B.SilkS")
		)
		(fp_line
			(start -0.67945 -0.3048)
			(end -0.67945 0.3048)
			(stroke
				(width 0.1)
				(type default)
			)
			(layer "B.Fab")
		)
		(fp_line
			(start -0.67945 0.3048)
			(end -0.120396 0.3048)
			(stroke
				(width 0.1)
				(type default)
			)
			(layer "B.Fab")
		)
		(fp_line
			(start -0.12065 -0.3048)
			(end -0.67945 -0.3048)
			(stroke
				(width 0.1)
				(type default)
			)
			(layer "B.Fab")
		)
		(fp_line
			(start -0.12065 -0.2794)
			(end -0.12065 -0.3048)
			(stroke
				(width 0.1)
				(type default)
			)
			(layer "B.Fab")
		)
		(fp_line
			(start -0.120396 0.2794)
			(end 0.12065 0.2794)
			(stroke
				(width 0.1)
				(type default)
			)
			(layer "B.Fab")
		)
		(fp_line
			(start -0.120396 0.3048)
			(end -0.120396 0.2794)
			(stroke
				(width 0.1)
				(type default)
			)
			(layer "B.Fab")
		)
		(fp_line
			(start 0.12065 -0.305054)
			(end 0.12065 -0.2794)
			(stroke
				(width 0.1)
				(type default)
			)
			(layer "B.Fab")
		)
		(fp_line
			(start 0.12065 -0.2794)
			(end -0.12065 -0.2794)
			(stroke
				(width 0.1)
				(type default)
			)
			(layer "B.Fab")
		)
		(fp_line
			(start 0.12065 0.2794)
			(end 0.12065 0.3048)
			(stroke
				(width 0.1)
				(type default)
			)
			(layer "B.Fab")
		)
		(fp_line
			(start 0.12065 0.3048)
			(end 0.67945 0.3048)
			(stroke
				(width 0.1)
				(type default)
			)
			(layer "B.Fab")
		)
		(fp_line
			(start 0.67945 -0.305054)
			(end 0.12065 -0.305054)
			(stroke
				(width 0.1)
				(type default)
			)
			(layer "B.Fab")
		)
		(fp_line
			(start 0.67945 0.3048)
			(end 0.67945 -0.305054)
			(stroke
				(width 0.1)
				(type default)
			)
			(layer "B.Fab")
		)
		(pad "1" smd circle
			(at 0.40005 0 180)
			(size 0 0)
			(layers "B.Cu" "B.Mask" "B.Paste")
			(net "PVDDCR_SOC_P0")
		)
		(pad "2" smd circle
			(at -0.40005 0 180)
			(size 0 0)
			(layers "B.Cu" "B.Mask" "B.Paste")
			(net "GND")
		)
	)
)
